#ISCELL
  mstr_misc dns *
  *
#ISCELL
  pure_quanta quanta_title_block_c *
  *
#CELL
  pure_quanta q_res *
  page256_i121
#ISCELL
  pure_quanta_power universal_gnd *
  page256_i122
#ISCELL
  pure_quanta_power universal_gnd *
  page256_i125
#CELL
  pure_quanta 74lvc2g17gw *
  page256_i127
#ISCELL
  standard offpage *
  page256_i129
#ISCELL
  pure_quanta_power universal_gnd *
  page256_i132
#ISCELL
  pure_quanta_power universal_power *
  page256_i139
#CELL
  pure_quanta q_cap *
  page256_i140
#ISCELL
  pure_quanta_power universal_gnd *
  page256_i141
#ISCELL
  pure_quanta_power universal_gnd *
  page256_i142
#ISCELL
  standard offpage *
  page256_i146
#CELL
  pure_quanta q_res *
  page256_i147
#ISCELL
  pure_quanta_power universal_power *
  page256_i148
#CELL
  pure_quanta q_res *
  page256_i153
#CELL
  pure_quanta q_res *
  page256_i154
#CELL
  pure_quanta q_res *
  page256_i155
#CELL
  pure_quanta q_res *
  page256_i156
#ISCELL
  pure_quanta_power universal_gnd *
  page256_i159
#CELL
  pure_quanta q_res *
  page256_i160
#ISCELL
  pure_quanta_power universal_power *
  page256_i161
#CELL
  pure_quanta q_res *
  page256_i162
#ISCELL
  standard offpage *
  page256_i163
#ISCELL
  pure_quanta_power universal_power *
  page256_i165
#CELL
  pure_quanta q_cap *
  page256_i166
#ISCELL
  pure_quanta_power universal_gnd *
  page256_i167
#CELL
  pure_quanta q_res *
  page256_i170
#CELL
  pure_quanta q_res *
  page256_i171
#ISCELL
  standard offpage *
  page256_i172
#ISCELL
  standard offpage *
  page256_i173
#ISCELL
  pure_quanta_power universal_power *
  page256_i174
#ISCELL
  standard offpage *
  page256_i177
#ISCELL
  pure_quanta_power universal_gnd *
  page256_i178
#ISCELL
  standard offpage *
  page256_i180
#CELL
  pure_quanta q_res *
  page256_i181
#ISCELL
  pure_quanta_power universal_power *
  page256_i183
#ISCELL
  pure_quanta_power universal_gnd *
  page256_i184
#CELL
  pure_quanta q_res *
  page256_i190
#CELL
  pure_quanta q_res *
  page256_i191
#CELL
  pure_quanta q_res *
  page256_i192
#CELL
  pure_quanta q_res *
  page256_i193
#CELL
  pure_quanta q_res *
  page256_i194
#CELL
  pure_quanta 74lvc1g126se7 *
  page256_i195
#ISCELL
  pure_quanta_power universal_gnd *
  page256_i196
#CELL
  pure_quanta q_res *
  page256_i197
#CELL
  pure_quanta q_res *
  page256_i198
#ISCELL
  pure_quanta_power universal_power *
  page256_i199
#CELL
  pure_quanta q_res *
  page256_i200
#ISCELL
  pure_quanta_power universal_power *
  page256_i201
#CELL
  pure_quanta q_res *
  page256_i203
#CELL
  pure_quanta q_res *
  page256_i204
#CELL
  pure_quanta 74lvc2g17gw *
  page256_i65
#ISCELL
  pure_quanta_power universal_power *
  page256_i67
#CELL
  pure_quanta q_res *
  page256_i68
#ISCELL
  pure_quanta_power universal_gnd *
  page256_i69
#ISCELL
  standard offpage *
  page256_i70
#ISCELL
  pure_quanta_power universal_power *
  page256_i71
#ISCELL
  pure_quanta_power universal_gnd *
  page256_i74
#ISCELL
  standard offpage *
  page256_i75
#ISCELL
  pure_quanta_power universal_gnd *
  page256_i76
#CELL
  pure_quanta q_res *
  page256_i78
#ISCELL
  standard offpage *
  page256_i79
#ISCELL
  pure_quanta_power universal_power *
  page256_i80
#ISCELL
  standard offpage *
  page256_i82
#ISCELL
  pure_quanta_power universal_power *
  page256_i83
#ISCELL
  pure_quanta_power universal_power *
  page256_i87
#ISCELL
  pure_quanta_power universal_gnd *
  page256_i88
#CELL
  pure_quanta q_cap *
  page256_i89
#CELL
  pure_quanta q_res *
  page256_i92
#CELL
  pure_quanta q_res *
  page256_i93
